# T6G (Grand Teton) — schematic netlist excerpt (pin names and nets, part order shuffled) for the footprints in the layout excerpt that follows; sources: Cadence DE-HDL packaged netlist, KiCad conversion of 04192023_DAF0TMB3IC0_F0TG_MB_C_brd_V02_OCP.brd

R9005  Q_RES  4.7K 5% CHIP  pkg 0402LF  page 123 : A = P3V3_AUX ; B = PRSNT_CABLE_SWB_B1_ISO_N
PL6503  Q_INDUCTOR  100NH/16A IND  pkg SMLF  page 361 : \1\ = P12V_AUX ; \2\ = SW_P12V_AUX_P1V8_RETIMER_CPU1_FLT
C2013  Q_CAP  0.1UF 25V 10% X7R  pkg 0402  page 237 : A = P3V3_AUX ; B = GND

(kicad_pcb
	(version 20260206)
	(generator "pcbnew")
	(generator_version "10.0")
	(general
		(thickness 1.6)
		(legacy_teardrops no)
	)
	(paper "A4")
	(title_block
		(title "04192023_DAF0TMB3IC0_F0TG_MB_C_brd_V02_OCP.brd")
		(comment 1 "Grand Teton / footprints 3125-3127 of 8354")
	)
	(layers
		(0 "F.Cu" signal "TOP")
		(4 "In1.Cu" signal "GND")
		(6 "In2.Cu" signal "IN1")
		(8 "In3.Cu" signal "GND1")
		(10 "In4.Cu" signal "IN2")
		(12 "In5.Cu" signal "GND2")
		(14 "In6.Cu" signal "IN3")
		(16 "In7.Cu" signal "GND3")
		(18 "In8.Cu" signal "VCC")
		(20 "In9.Cu" signal "VCC1")
		(22 "In10.Cu" signal "GND4")
		(24 "In11.Cu" signal "IN4")
		(26 "In12.Cu" signal "GND5")
		(28 "In13.Cu" signal "IN5")
		(30 "In14.Cu" signal "GND6")
		(32 "In15.Cu" signal "IN6")
		(34 "In16.Cu" signal "GND7")
		(2 "B.Cu" signal "BOTTOM")
		(9 "F.Adhes" user "F.Adhesive")
		(11 "B.Adhes" user "B.Adhesive")
		(13 "F.Paste" user "Package Geometry/Pastemask Top")
		(15 "B.Paste" user "Package Geometry/Pastemask Bottom")
		(5 "F.SilkS" user "Ref Des/Silkscreen Top")
		(7 "B.SilkS" user "Ref Des/Silkscreen Bottom")
		(1 "F.Mask" user "Board Geometry/Soldermask Top")
		(3 "B.Mask" user "Board Geometry/Soldermask Bottom")
		(17 "Dwgs.User" user "User.Drawings")
		(19 "Cmts.User" user "User.Comments")
		(21 "Eco1.User" user "User.Eco1")
		(23 "Eco2.User" user "User.Eco2")
		(25 "Edge.Cuts" user "Board Geometry/Outline")
		(27 "Margin" user)
		(31 "F.CrtYd" user "Package Geometry/Place Bound Top")
		(29 "B.CrtYd" user "Package Geometry/Place Bound Bottom")
		(35 "F.Fab" user "Ref Des/Assembly Top")
		(33 "B.Fab" user "Ref Des/Assembly Bottom")
	)
	(footprint ""
		(layer "F.Cu")
		(at 225.420428 -271.407382)
		(property "Reference" "PL6503"
			(at 1.147572 3.337052 0)
			(unlocked yes)
			(layer "F.SilkS")
			(effects
				(font
					(size 0.7874 0.5842)
					(thickness 0.1524)
				)
				(justify left)
			)
		)
		(property "Value" ""
			(at 0 0 0)
			(layer "F.Fab")
			(effects
				(font
					(size 1.27 1.27)
				)
			)
		)
		(duplicate_pad_numbers_are_jumpers no)
		(fp_line
			(start -2.249932 -2.249932)
			(end 2.249932 -2.249932)
			(stroke
				(width 0.1524)
				(type default)
			)
			(layer "F.SilkS")
		)
		(fp_line
			(start -2.249932 -1.3843)
			(end -2.249932 -2.249932)
			(stroke
				(width 0.1524)
				(type default)
			)
			(layer "F.SilkS")
		)
		(fp_line
			(start -2.249932 2.249932)
			(end -2.249932 1.3843)
			(stroke
				(width 0.1524)
				(type default)
			)
			(layer "F.SilkS")
		)
		(fp_line
			(start 2.249932 -2.249932)
			(end 2.249932 -1.3843)
			(stroke
				(width 0.1524)
				(type default)
			)
			(layer "F.SilkS")
		)
		(fp_line
			(start 2.249932 1.3843)
			(end 2.249932 2.249932)
			(stroke
				(width 0.1524)
				(type default)
			)
			(layer "F.SilkS")
		)
		(fp_line
			(start 2.249932 2.249932)
			(end -2.249932 2.249932)
			(stroke
				(width 0.1524)
				(type default)
			)
			(layer "F.SilkS")
		)
		(fp_line
			(start -2.249932 -2.249932)
			(end 2.249932 -2.249932)
			(stroke
				(width 0.1)
				(type default)
			)
			(layer "F.Fab")
		)
		(fp_line
			(start -2.249932 2.249932)
			(end -2.249932 -2.249932)
			(stroke
				(width 0.1)
				(type default)
			)
			(layer "F.Fab")
		)
		(fp_line
			(start 2.249932 -2.249932)
			(end 2.249932 2.249932)
			(stroke
				(width 0.1)
				(type default)
			)
			(layer "F.Fab")
		)
		(fp_line
			(start 2.249932 2.249932)
			(end -2.249932 2.249932)
			(stroke
				(width 0.1)
				(type default)
			)
			(layer "F.Fab")
		)
		(pad "1" smd rect
			(at -1.82499 0)
			(size 1.0668 2.5146)
			(layers "F.Cu" "F.Mask" "F.Paste")
			(net "P12V_AUX")
		)
		(pad "2" smd rect
			(at 1.82499 0)
			(size 1.0668 2.5146)
			(layers "F.Cu" "F.Mask" "F.Paste")
			(net "SW_P12V_AUX_P1V8_RETIMER_CPU1_FLT")
		)
	)
	(footprint ""
		(layer "F.Cu")
		(at 157.995366 -56.331358)
		(property "Reference" "C2013"
			(at 0 0 0)
			(layer "F.SilkS")
			(hide yes)
			(effects
				(font
					(size 1.27 1.27)
				)
			)
		)
		(property "Value" ""
			(at 0 0 0)
			(layer "F.Fab")
			(effects
				(font
					(size 1.27 1.27)
				)
			)
		)
		(duplicate_pad_numbers_are_jumpers no)
		(fp_line
			(start -0.7874 -0.4064)
			(end 0.7874 -0.4064)
			(stroke
				(width 0.1524)
				(type default)
			)
			(layer "F.SilkS")
		)
		(fp_line
			(start -0.7874 0.4064)
			(end -0.7874 -0.4064)
			(stroke
				(width 0.1524)
				(type default)
			)
			(layer "F.SilkS")
		)
		(fp_line
			(start 0.7874 -0.4064)
			(end 0.7874 0.4064)
			(stroke
				(width 0.1524)
				(type default)
			)
			(layer "F.SilkS")
		)
		(fp_line
			(start 0.7874 0.4064)
			(end -0.7874 0.4064)
			(stroke
				(width 0.1524)
				(type default)
			)
			(layer "F.SilkS")
		)
		(fp_line
			(start -0.67945 -0.305054)
			(end -0.12065 -0.305054)
			(stroke
				(width 0.1)
				(type default)
			)
			(layer "F.Fab")
		)
		(fp_line
			(start -0.67945 0.3048)
			(end -0.67945 -0.305054)
			(stroke
				(width 0.1)
				(type default)
			)
			(layer "F.Fab")
		)
		(fp_line
			(start -0.12065 -0.305054)
			(end -0.12065 -0.2794)
			(stroke
				(width 0.1)
				(type default)
			)
			(layer "F.Fab")
		)
		(fp_line
			(start -0.12065 -0.2794)
			(end 0.12065 -0.2794)
			(stroke
				(width 0.1)
				(type default)
			)
			(layer "F.Fab")
		)
		(fp_line
			(start -0.12065 0.2794)
			(end -0.12065 0.3048)
			(stroke
				(width 0.1)
				(type default)
			)
			(layer "F.Fab")
		)
		(fp_line
			(start -0.12065 0.3048)
			(end -0.67945 0.3048)
			(stroke
				(width 0.1)
				(type default)
			)
			(layer "F.Fab")
		)
		(fp_line
			(start 0.120396 0.2794)
			(end -0.12065 0.2794)
			(stroke
				(width 0.1)
				(type default)
			)
			(layer "F.Fab")
		)
		(fp_line
			(start 0.120396 0.3048)
			(end 0.120396 0.2794)
			(stroke
				(width 0.1)
				(type default)
			)
			(layer "F.Fab")
		)
		(fp_line
			(start 0.12065 -0.3048)
			(end 0.67945 -0.3048)
			(stroke
				(width 0.1)
				(type default)
			)
			(layer "F.Fab")
		)
		(fp_line
			(start 0.12065 -0.2794)
			(end 0.12065 -0.3048)
			(stroke
				(width 0.1)
				(type default)
			)
			(layer "F.Fab")
		)
		(fp_line
			(start 0.67945 -0.3048)
			(end 0.67945 0.3048)
			(stroke
				(width 0.1)
				(type default)
			)
			(layer "F.Fab")
		)
		(fp_line
			(start 0.67945 0.3048)
			(end 0.120396 0.3048)
			(stroke
				(width 0.1)
				(type default)
			)
			(layer "F.Fab")
		)
		(pad "1" smd circle
			(at -0.40005 0)
			(size 0 0)
			(layers "F.Cu" "F.Mask" "F.Paste")
			(net "P3V3_AUX")
		)
		(pad "2" smd circle
			(at 0.40005 0)
			(size 0 0)
			(layers "F.Cu" "F.Mask" "F.Paste")
			(net "GND")
		)
	)
	(footprint ""
		(layer "F.Cu")
		(at 364.362238 -411.369764)
		(property "Reference" "R9005"
			(at 0 0 0)
			(layer "F.SilkS")
			(hide yes)
			(effects
				(font
					(size 1.27 1.27)
				)
			)
		)
		(property "Value" ""
			(at 0 0 0)
			(layer "F.Fab")
			(effects
				(font
					(size 1.27 1.27)
				)
			)
		)
		(duplicate_pad_numbers_are_jumpers no)
		(fp_line
			(start -0.7874 -0.4064)
			(end 0.7874 -0.4064)
			(stroke
				(width 0.1524)
				(type default)
			)
			(layer "F.SilkS")
		)
		(fp_line
			(start -0.7874 0.4064)
			(end -0.7874 -0.4064)
			(stroke
				(width 0.1524)
				(type default)
			)
			(layer "F.SilkS")
		)
		(fp_line
			(start 0.7874 -0.4064)
			(end 0.7874 0.4064)
			(stroke
				(width 0.1524)
				(type default)
			)
			(layer "F.SilkS")
		)
		(fp_line
			(start 0.7874 0.4064)
			(end -0.7874 0.4064)
			(stroke
				(width 0.1524)
				(type default)
			)
			(layer "F.SilkS")
		)
		(fp_line
			(start -0.67945 -0.305054)
			(end -0.12065 -0.305054)
			(stroke
				(width 0.1)
				(type default)
			)
			(layer "F.Fab")
		)
		(fp_line
			(start -0.67945 0.3048)
			(end -0.67945 -0.305054)
			(stroke
				(width 0.1)
				(type default)
			)
			(layer "F.Fab")
		)
		(fp_line
			(start -0.12065 -0.305054)
			(end -0.12065 -0.2794)
			(stroke
				(width 0.1)
				(type default)
			)
			(layer "F.Fab")
		)
		(fp_line
			(start -0.12065 -0.2794)
			(end 0.12065 -0.2794)
			(stroke
				(width 0.1)
				(type default)
			)
			(layer "F.Fab")
		)
		(fp_line
			(start -0.12065 0.2794)
			(end -0.12065 0.3048)
			(stroke
				(width 0.1)
				(type default)
			)
			(layer "F.Fab")
		)
		(fp_line
			(start -0.12065 0.3048)
			(end -0.67945 0.3048)
			(stroke
				(width 0.1)
				(type default)
			)
			(layer "F.Fab")
		)
		(fp_line
			(start 0.120396 0.2794)
			(end -0.12065 0.2794)
			(stroke
				(width 0.1)
				(type default)
			)
			(layer "F.Fab")
		)
		(fp_line
			(start 0.120396 0.3048)
			(end 0.120396 0.2794)
			(stroke
				(width 0.1)
				(type default)
			)
			(layer "F.Fab")
		)
		(fp_line
			(start 0.12065 -0.3048)
			(end 0.67945 -0.3048)
			(stroke
				(width 0.1)
				(type default)
			)
			(layer "F.Fab")
		)
		(fp_line
			(start 0.12065 -0.2794)
			(end 0.12065 -0.3048)
			(stroke
				(width 0.1)
				(type default)
			)
			(layer "F.Fab")
		)
		(fp_line
			(start 0.67945 -0.3048)
			(end 0.67945 0.3048)
			(stroke
				(width 0.1)
				(type default)
			)
			(layer "F.Fab")
		)
		(fp_line
			(start 0.67945 0.3048)
			(end 0.120396 0.3048)
			(stroke
				(width 0.1)
				(type default)
			)
			(layer "F.Fab")
		)
		(pad "1" smd circle
			(at -0.40005 0)
			(size 0 0)
			(layers "F.Cu" "F.Mask" "F.Paste")
			(net "P3V3_AUX")
		)
		(pad "2" smd circle
			(at 0.40005 0)
			(size 0 0)
			(layers "F.Cu" "F.Mask" "F.Paste")
			(net "PRSNT_CABLE_SWB_B1_ISO_N")
		)
	)
)
